(kicad_pcb
	(version 20260206)
	(generator "pcbnew")
	(generator_version "10.0")
	(general
		(thickness 1.6)
		(legacy_teardrops no)
	)
	(paper "A4")
	(title_block
		(title "01162023_DA0F0TEBIF0_F0T_Expander_BD_F_brd_V02_OCP.brd")
		(comment 1 "Grand Teton / footprints 1723-1728 of 9728")
	)
	(layers
		(0 "F.Cu" signal "TOP")
		(4 "In1.Cu" signal "GND")
		(6 "In2.Cu" signal "VCC")
		(8 "In3.Cu" signal "VCC1")
		(10 "In4.Cu" signal "GND1")
		(12 "In5.Cu" signal "IN1")
		(14 "In6.Cu" signal "GND2")
		(16 "In7.Cu" signal "IN2")
		(18 "In8.Cu" signal "GND3")
		(20 "In9.Cu" signal "IN3")
		(22 "In10.Cu" signal "GND4")
		(24 "In11.Cu" signal "IN4")
		(26 "In12.Cu" signal "GND5")
		(28 "In13.Cu" signal "IN5")
		(30 "In14.Cu" signal "GND6")
		(32 "In15.Cu" signal "IN6")
		(34 "In16.Cu" signal "GND7")
		(2 "B.Cu" signal "BOTTOM")
		(9 "F.Adhes" user "F.Adhesive")
		(11 "B.Adhes" user "B.Adhesive")
		(13 "F.Paste" user "Package Geometry/Pastemask Top")
		(15 "B.Paste" user "Package Geometry/Pastemask Bottom")
		(5 "F.SilkS" user "Ref Des/Silkscreen Top")
		(7 "B.SilkS" user "Ref Des/Silkscreen Bottom")
		(1 "F.Mask" user "Board Geometry/Soldermask Top")
		(3 "B.Mask" user "Board Geometry/Soldermask Bottom")
		(17 "Dwgs.User" user "User.Drawings")
		(19 "Cmts.User" user "User.Comments")
		(21 "Eco1.User" user "User.Eco1")
		(23 "Eco2.User" user "User.Eco2")
		(25 "Edge.Cuts" user "Board Geometry/Outline")
		(27 "Margin" user)
		(31 "F.CrtYd" user "Package Geometry/Place Bound Top")
		(29 "B.CrtYd" user "Package Geometry/Place Bound Bottom")
		(35 "F.Fab" user "Ref Des/Assembly Top")
		(33 "B.Fab" user "Ref Des/Assembly Bottom")
	)
	(footprint ""
		(layer "F.Cu")
		(at 314.119768 8.109712 180)
		(property "Reference" "DE13T_1"
			(at 2.817368 3.079242 0)
			(unlocked yes)
			(layer "F.SilkS")
			(effects
				(font
					(size 0.7874 0.5842)
					(thickness 0.1524)
				)
				(justify left)
			)
		)
		(property "Value" ""
			(at 0 0 180)
			(layer "F.Fab")
			(effects
				(font
					(size 1.27 1.27)
				)
			)
		)
		(duplicate_pad_numbers_are_jumpers no)
		(fp_line
			(start 1.2192 2.1082)
			(end -1.2192 2.1082)
			(stroke
				(width 0.1524)
				(type default)
			)
			(layer "F.SilkS")
		)
		(fp_line
			(start 1.2192 -2.1082)
			(end 1.2192 2.1082)
			(stroke
				(width 0.1524)
				(type default)
			)
			(layer "F.SilkS")
		)
		(fp_line
			(start -1.2192 2.1082)
			(end -1.2192 -2.1082)
			(stroke
				(width 0.1524)
				(type default)
			)
			(layer "F.SilkS")
		)
		(fp_line
			(start -1.2192 -2.1082)
			(end 1.2192 -2.1082)
			(stroke
				(width 0.1524)
				(type default)
			)
			(layer "F.SilkS")
		)
		(pad "" np_thru_hole circle
			(at -2.8829 -1.27 90)
			(size 1.0414 1.0414)
			(drill 1.0414)
			(layers "*.Cu" "*.Mask")
			(clearance 0.381)
			(thermal_gap 0.381)
		)
		(pad "" np_thru_hole circle
			(at -2.8829 1.27 90)
			(size 1.0414 1.0414)
			(drill 1.0414)
			(layers "*.Cu" "*.Mask")
			(clearance 0.381)
			(thermal_gap 0.381)
		)
		(pad "" np_thru_hole circle
			(at 3.4671 -1.27 90)
			(size 1.0414 1.0414)
			(drill 1.0414)
			(layers "*.Cu" "*.Mask")
			(clearance 0.381)
			(thermal_gap 0.381)
		)
		(pad "" np_thru_hole circle
			(at 3.4671 1.27 90)
			(size 1.0414 1.0414)
			(drill 1.0414)
			(layers "*.Cu" "*.Mask")
			(clearance 0.381)
			(thermal_gap 0.381)
		)
		(pad "1" smd rect
			(at 0.8255 -0.249936 90)
			(size 0.3048 0.508)
			(layers "F.Cu" "F.Mask" "F.Paste")
			(net "85_10INCH_IN1_DP")
		)
		(pad "2" smd rect
			(at 0.8255 0.249936 90)
			(size 0.3048 0.508)
			(layers "F.Cu" "F.Mask" "F.Paste")
			(net "85_10INCH_IN1_DN")
		)
		(pad "3" smd circle
			(at 0 0 180)
			(size 0 0)
			(layers "F.Cu" "F.Mask" "F.Paste")
			(net "COUPON_GND2")
		)
		(zone
			(layer "F.Cu")
			(hatch none 0.5)
			(connect_pads
				(clearance 0)
			)
			(min_thickness 0.25)
			(keepout
				(tracks not_allowed)
				(vias allowed)
				(pads allowed)
				(copperpour not_allowed)
				(footprints allowed)
			)
			(placement
				(enabled no)
				(sheetname "")
			)
			(fill
				(thermal_gap 0.5)
				(thermal_bridge_width 0.5)
				(island_removal_mode 0)
			)
			(polygon
				(pts
					(xy 313.002168 8.658352) (xy 313.002168 8.562848) (xy 313.599068 8.562848) (xy 313.599068 8.156448)
					(xy 313.002168 8.156448) (xy 313.002168 8.062976) (xy 313.599068 8.062976) (xy 313.599068 7.656576)
					(xy 313.002168 7.656576) (xy 313.002168 7.561072) (xy 313.700668 7.561072) (xy 313.700668 8.658352)
				)
			)
		)
		(zone
			(layers "F.Cu" "B.Cu" "In1.Cu" "In2.Cu" "In3.Cu" "In4.Cu" "In5.Cu" "In6.Cu"
				"In7.Cu" "In8.Cu" "In9.Cu" "In10.Cu" "In11.Cu" "In12.Cu" "In13.Cu" "In14.Cu"
				"In15.Cu" "In16.Cu"
			)
			(hatch none 0.5)
			(connect_pads
				(clearance 0)
			)
			(min_thickness 0.25)
			(keepout
				(tracks not_allowed)
				(vias allowed)
				(pads allowed)
				(copperpour not_allowed)
				(footprints allowed)
			)
			(placement
				(enabled no)
				(sheetname "")
			)
			(fill
				(thermal_gap 0.5)
				(thermal_bridge_width 0.5)
				(island_removal_mode 0)
			)
			(polygon
				(pts
					(arc
						(start 311.579768 6.839712)
						(mid 309.725568 6.839712)
						(end 311.579768 6.839712)
					)
				)
			)
		)
		(zone
			(layers "F.Cu" "B.Cu" "In1.Cu" "In2.Cu" "In3.Cu" "In4.Cu" "In5.Cu" "In6.Cu"
				"In7.Cu" "In8.Cu" "In9.Cu" "In10.Cu" "In11.Cu" "In12.Cu" "In13.Cu" "In14.Cu"
				"In15.Cu" "In16.Cu"
			)
			(hatch none 0.5)
			(connect_pads
				(clearance 0)
			)
			(min_thickness 0.25)
			(keepout
				(tracks not_allowed)
				(vias allowed)
				(pads allowed)
				(copperpour not_allowed)
				(footprints allowed)
			)
			(placement
				(enabled no)
				(sheetname "")
			)
			(fill
				(thermal_gap 0.5)
				(thermal_bridge_width 0.5)
				(island_removal_mode 0)
			)
			(polygon
				(pts
					(arc
						(start 311.579768 9.379712)
						(mid 309.725568 9.379712)
						(end 311.579768 9.379712)
					)
				)
			)
		)
		(zone
			(layers "F.Cu" "B.Cu" "In1.Cu" "In2.Cu" "In3.Cu" "In4.Cu" "In5.Cu" "In6.Cu"
				"In7.Cu" "In8.Cu" "In9.Cu" "In10.Cu" "In11.Cu" "In12.Cu" "In13.Cu" "In14.Cu"
				"In15.Cu" "In16.Cu"
			)
			(hatch none 0.5)
			(connect_pads
				(clearance 0)
			)
			(min_thickness 0.25)
			(keepout
				(tracks not_allowed)
				(vias allowed)
				(pads allowed)
				(copperpour not_allowed)
				(footprints allowed)
			)
			(placement
				(enabled no)
				(sheetname "")
			)
			(fill
				(thermal_gap 0.5)
				(thermal_bridge_width 0.5)
				(island_removal_mode 0)
			)
			(polygon
				(pts
					(arc
						(start 317.929768 6.839712)
						(mid 316.075568 6.839712)
						(end 317.929768 6.839712)
					)
				)
			)
		)
		(zone
			(layers "F.Cu" "B.Cu" "In1.Cu" "In2.Cu" "In3.Cu" "In4.Cu" "In5.Cu" "In6.Cu"
				"In7.Cu" "In8.Cu" "In9.Cu" "In10.Cu" "In11.Cu" "In12.Cu" "In13.Cu" "In14.Cu"
				"In15.Cu" "In16.Cu"
			)
			(hatch none 0.5)
			(connect_pads
				(clearance 0)
			)
			(min_thickness 0.25)
			(keepout
				(tracks not_allowed)
				(vias allowed)
				(pads allowed)
				(copperpour not_allowed)
				(footprints allowed)
			)
			(placement
				(enabled no)
				(sheetname "")
			)
			(fill
				(thermal_gap 0.5)
				(thermal_bridge_width 0.5)
				(island_removal_mode 0)
			)
			(polygon
				(pts
					(arc
						(start 317.929768 9.379712)
						(mid 316.075568 9.379712)
						(end 317.929768 9.379712)
					)
				)
			)
		)
	)
	(footprint ""
		(layer "F.Cu")
		(at 185.89244 -28.225242 180)
		(property "Reference" "C299"
			(at 0 0 180)
			(layer "F.SilkS")
			(hide yes)
			(effects
				(font
					(size 1.27 1.27)
				)
			)
		)
		(property "Value" ""
			(at 0 0 180)
			(layer "F.Fab")
			(effects
				(font
					(size 1.27 1.27)
				)
			)
		)
		(duplicate_pad_numbers_are_jumpers no)
		(fp_line
			(start 0.299974 0.150114)
			(end -0.299974 0.150114)
			(stroke
				(width 0.1)
				(type default)
			)
			(layer "F.Fab")
		)
		(fp_line
			(start 0.299974 -0.150114)
			(end 0.299974 0.150114)
			(stroke
				(width 0.1)
				(type default)
			)
			(layer "F.Fab")
		)
		(fp_line
			(start -0.299974 0.150114)
			(end -0.299974 -0.150114)
			(stroke
				(width 0.1)
				(type default)
			)
			(layer "F.Fab")
		)
		(fp_line
			(start -0.299974 -0.150114)
			(end 0.299974 -0.150114)
			(stroke
				(width 0.1)
				(type default)
			)
			(layer "F.Fab")
		)
		(pad "1" smd rect
			(at -0.2667 0 180)
			(size 0.3048 0.381)
			(layers "F.Cu" "F.Mask" "F.Paste")
			(net "P5E_PEX1_STN2_TX_DN<36>")
		)
		(pad "2" smd rect
			(at 0.2667 0 180)
			(size 0.3048 0.381)
			(layers "F.Cu" "F.Mask" "F.Paste")
			(net "P5E_PEX1_STN2_TX_C_DN<36>")
		)
	)
	(footprint ""
		(layer "F.Cu")
		(at 355.854 -165.608 180)
		(property "Reference" "R4729"
			(at 0 0 180)
			(layer "F.SilkS")
			(hide yes)
			(effects
				(font
					(size 1.27 1.27)
				)
			)
		)
		(property "Value" ""
			(at 0 0 180)
			(layer "F.Fab")
			(effects
				(font
					(size 1.27 1.27)
				)
			)
		)
		(duplicate_pad_numbers_are_jumpers no)
		(fp_line
			(start 0.7874 0.4064)
			(end -0.7874 0.4064)
			(stroke
				(width 0.1524)
				(type default)
			)
			(layer "F.SilkS")
		)
		(fp_line
			(start 0.7874 -0.4064)
			(end 0.7874 0.4064)
			(stroke
				(width 0.1524)
				(type default)
			)
			(layer "F.SilkS")
		)
		(fp_line
			(start -0.7874 0.4064)
			(end -0.7874 -0.4064)
			(stroke
				(width 0.1524)
				(type default)
			)
			(layer "F.SilkS")
		)
		(fp_line
			(start -0.7874 -0.4064)
			(end 0.7874 -0.4064)
			(stroke
				(width 0.1524)
				(type default)
			)
			(layer "F.SilkS")
		)
		(fp_line
			(start 0.67945 0.3048)
			(end 0.120396 0.3048)
			(stroke
				(width 0.1)
				(type default)
			)
			(layer "F.Fab")
		)
		(fp_line
			(start 0.67945 -0.3048)
			(end 0.67945 0.3048)
			(stroke
				(width 0.1)
				(type default)
			)
			(layer "F.Fab")
		)
		(fp_line
			(start 0.12065 -0.2794)
			(end 0.12065 -0.3048)
			(stroke
				(width 0.1)
				(type default)
			)
			(layer "F.Fab")
		)
		(fp_line
			(start 0.12065 -0.3048)
			(end 0.67945 -0.3048)
			(stroke
				(width 0.1)
				(type default)
			)
			(layer "F.Fab")
		)
		(fp_line
			(start 0.120396 0.3048)
			(end 0.120396 0.2794)
			(stroke
				(width 0.1)
				(type default)
			)
			(layer "F.Fab")
		)
		(fp_line
			(start 0.120396 0.2794)
			(end -0.12065 0.2794)
			(stroke
				(width 0.1)
				(type default)
			)
			(layer "F.Fab")
		)
		(fp_line
			(start -0.12065 0.3048)
			(end -0.67945 0.3048)
			(stroke
				(width 0.1)
				(type default)
			)
			(layer "F.Fab")
		)
		(fp_line
			(start -0.12065 0.2794)
			(end -0.12065 0.3048)
			(stroke
				(width 0.1)
				(type default)
			)
			(layer "F.Fab")
		)
		(fp_line
			(start -0.12065 -0.2794)
			(end 0.12065 -0.2794)
			(stroke
				(width 0.1)
				(type default)
			)
			(layer "F.Fab")
		)
		(fp_line
			(start -0.12065 -0.305054)
			(end -0.12065 -0.2794)
			(stroke
				(width 0.1)
				(type default)
			)
			(layer "F.Fab")
		)
		(fp_line
			(start -0.67945 0.3048)
			(end -0.67945 -0.305054)
			(stroke
				(width 0.1)
				(type default)
			)
			(layer "F.Fab")
		)
		(fp_line
			(start -0.67945 -0.305054)
			(end -0.12065 -0.305054)
			(stroke
				(width 0.1)
				(type default)
			)
			(layer "F.Fab")
		)
		(pad "1" smd circle
			(at -0.40005 0 180)
			(size 0 0)
			(layers "F.Cu" "F.Mask" "F.Paste")
			(net "P3V3_AUX")
		)
		(pad "2" smd circle
			(at 0.40005 0 180)
			(size 0 0)
			(layers "F.Cu" "F.Mask" "F.Paste")
			(net "NIC5_PEX_PWR_EN_R")
		)
	)
	(footprint ""
		(layer "F.Cu")
		(at 394.787628 -25.342342 -90)
		(property "Reference" "R449"
			(at 0 0 270)
			(layer "F.SilkS")
			(hide yes)
			(effects
				(font
					(size 1.27 1.27)
				)
			)
		)
		(property "Value" ""
			(at 0 0 270)
			(layer "F.Fab")
			(effects
				(font
					(size 1.27 1.27)
				)
			)
		)
		(duplicate_pad_numbers_are_jumpers no)
		(fp_line
			(start -0.7874 0.4064)
			(end -0.7874 -0.4064)
			(stroke
				(width 0.1524)
				(type default)
			)
			(layer "F.SilkS")
		)
		(fp_line
			(start 0.7874 0.4064)
			(end -0.7874 0.4064)
			(stroke
				(width 0.1524)
				(type default)
			)
			(layer "F.SilkS")
		)
		(fp_line
			(start -0.7874 -0.4064)
			(end 0.7874 -0.4064)
			(stroke
				(width 0.1524)
				(type default)
			)
			(layer "F.SilkS")
		)
		(fp_line
			(start 0.7874 -0.4064)
			(end 0.7874 0.4064)
			(stroke
				(width 0.1524)
				(type default)
			)
			(layer "F.SilkS")
		)
		(fp_line
			(start -0.67945 0.3048)
			(end -0.67945 -0.305054)
			(stroke
				(width 0.1)
				(type default)
			)
			(layer "F.Fab")
		)
		(fp_line
			(start -0.12065 0.3048)
			(end -0.67945 0.3048)
			(stroke
				(width 0.1)
				(type default)
			)
			(layer "F.Fab")
		)
		(fp_line
			(start 0.120396 0.3048)
			(end 0.120396 0.2794)
			(stroke
				(width 0.1)
				(type default)
			)
			(layer "F.Fab")
		)
		(fp_line
			(start 0.67945 0.3048)
			(end 0.120396 0.3048)
			(stroke
				(width 0.1)
				(type default)
			)
			(layer "F.Fab")
		)
		(fp_line
			(start -0.12065 0.2794)
			(end -0.12065 0.3048)
			(stroke
				(width 0.1)
				(type default)
			)
			(layer "F.Fab")
		)
		(fp_line
			(start 0.120396 0.2794)
			(end -0.12065 0.2794)
			(stroke
				(width 0.1)
				(type default)
			)
			(layer "F.Fab")
		)
		(fp_line
			(start -0.12065 -0.2794)
			(end 0.12065 -0.2794)
			(stroke
				(width 0.1)
				(type default)
			)
			(layer "F.Fab")
		)
		(fp_line
			(start 0.12065 -0.2794)
			(end 0.12065 -0.3048)
			(stroke
				(width 0.1)
				(type default)
			)
			(layer "F.Fab")
		)
		(fp_line
			(start 0.12065 -0.3048)
			(end 0.67945 -0.3048)
			(stroke
				(width 0.1)
				(type default)
			)
			(layer "F.Fab")
		)
		(fp_line
			(start 0.67945 -0.3048)
			(end 0.67945 0.3048)
			(stroke
				(width 0.1)
				(type default)
			)
			(layer "F.Fab")
		)
		(fp_line
			(start -0.67945 -0.305054)
			(end -0.12065 -0.305054)
			(stroke
				(width 0.1)
				(type default)
			)
			(layer "F.Fab")
		)
		(fp_line
			(start -0.12065 -0.305054)
			(end -0.12065 -0.2794)
			(stroke
				(width 0.1)
				(type default)
			)
			(layer "F.Fab")
		)
		(pad "1" smd circle
			(at -0.40005 0 270)
			(size 0 0)
			(layers "F.Cu" "F.Mask" "F.Paste")
			(net "GND")
		)
		(pad "2" smd circle
			(at 0.40005 0 270)
			(size 0 0)
			(layers "F.Cu" "F.Mask" "F.Paste")
			(net "DUALPORT_N_SSD13")
		)
	)
	(footprint ""
		(layer "F.Cu")
		(at 356.071932 -24.807418)
		(property "Reference" "R446"
			(at 0 0 0)
			(layer "F.SilkS")
			(hide yes)
			(effects
				(font
					(size 1.27 1.27)
				)
			)
		)
		(property "Value" ""
			(at 0 0 0)
			(layer "F.Fab")
			(effects
				(font
					(size 1.27 1.27)
				)
			)
		)
		(duplicate_pad_numbers_are_jumpers no)
		(fp_line
			(start -0.7874 -0.4064)
			(end 0.7874 -0.4064)
			(stroke
				(width 0.1524)
				(type default)
			)
			(layer "F.SilkS")
		)
		(fp_line
			(start -0.7874 0.4064)
			(end -0.7874 -0.4064)
			(stroke
				(width 0.1524)
				(type default)
			)
			(layer "F.SilkS")
		)
		(fp_line
			(start 0.7874 -0.4064)
			(end 0.7874 0.4064)
			(stroke
				(width 0.1524)
				(type default)
			)
			(layer "F.SilkS")
		)
		(fp_line
			(start 0.7874 0.4064)
			(end -0.7874 0.4064)
			(stroke
				(width 0.1524)
				(type default)
			)
			(layer "F.SilkS")
		)
		(fp_line
			(start -0.67945 -0.305054)
			(end -0.12065 -0.305054)
			(stroke
				(width 0.1)
				(type default)
			)
			(layer "F.Fab")
		)
		(fp_line
			(start -0.67945 0.3048)
			(end -0.67945 -0.305054)
			(stroke
				(width 0.1)
				(type default)
			)
			(layer "F.Fab")
		)
		(fp_line
			(start -0.12065 -0.305054)
			(end -0.12065 -0.2794)
			(stroke
				(width 0.1)
				(type default)
			)
			(layer "F.Fab")
		)
		(fp_line
			(start -0.12065 -0.2794)
			(end 0.12065 -0.2794)
			(stroke
				(width 0.1)
				(type default)
			)
			(layer "F.Fab")
		)
		(fp_line
			(start -0.12065 0.2794)
			(end -0.12065 0.3048)
			(stroke
				(width 0.1)
				(type default)
			)
			(layer "F.Fab")
		)
		(fp_line
			(start -0.12065 0.3048)
			(end -0.67945 0.3048)
			(stroke
				(width 0.1)
				(type default)
			)
			(layer "F.Fab")
		)
		(fp_line
			(start 0.120396 0.2794)
			(end -0.12065 0.2794)
			(stroke
				(width 0.1)
				(type default)
			)
			(layer "F.Fab")
		)
		(fp_line
			(start 0.120396 0.3048)
			(end 0.120396 0.2794)
			(stroke
				(width 0.1)
				(type default)
			)
			(layer "F.Fab")
		)
		(fp_line
			(start 0.12065 -0.3048)
			(end 0.67945 -0.3048)
			(stroke
				(width 0.1)
				(type default)
			)
			(layer "F.Fab")
		)
		(fp_line
			(start 0.12065 -0.2794)
			(end 0.12065 -0.3048)
			(stroke
				(width 0.1)
				(type default)
			)
			(layer "F.Fab")
		)
		(fp_line
			(start 0.67945 -0.3048)
			(end 0.67945 0.3048)
			(stroke
				(width 0.1)
				(type default)
			)
			(layer "F.Fab")
		)
		(fp_line
			(start 0.67945 0.3048)
			(end 0.120396 0.3048)
			(stroke
				(width 0.1)
				(type default)
			)
			(layer "F.Fab")
		)
		(pad "1" smd circle
			(at -0.40005 0)
			(size 0 0)
			(layers "F.Cu" "F.Mask" "F.Paste")
			(net "P3V3_SSD12")
		)
		(pad "2" smd circle
			(at 0.40005 0)
			(size 0 0)
			(layers "F.Cu" "F.Mask" "F.Paste")
			(net "PU_CLKREQ12")
		)
	)
	(footprint ""
		(layer "F.Cu")
		(at 283.416502 -356.244906 90)
		(property "Reference" "C597"
			(at 0 0 90)
			(layer "F.SilkS")
			(hide yes)
			(effects
				(font
					(size 1.27 1.27)
				)
			)
		)
		(property "Value" ""
			(at 0 0 90)
			(layer "F.Fab")
			(effects
				(font
					(size 1.27 1.27)
				)
			)
		)
		(duplicate_pad_numbers_are_jumpers no)
		(fp_line
			(start 0.299974 -0.150114)
			(end 0.299974 0.150114)
			(stroke
				(width 0.1)
				(type default)
			)
			(layer "F.Fab")
		)
		(fp_line
			(start -0.299974 -0.150114)
			(end 0.299974 -0.150114)
			(stroke
				(width 0.1)
				(type default)
			)
			(layer "F.Fab")
		)
		(fp_line
			(start 0.299974 0.150114)
			(end -0.299974 0.150114)
			(stroke
				(width 0.1)
				(type default)
			)
			(layer "F.Fab")
		)
		(fp_line
			(start -0.299974 0.150114)
			(end -0.299974 -0.150114)
			(stroke
				(width 0.1)
				(type default)
			)
			(layer "F.Fab")
		)
		(pad "1" smd rect
			(at -0.2667 0 90)
			(size 0.3048 0.381)
			(layers "F.Cu" "F.Mask" "F.Paste")
			(net "P5E_PEX2_STN7_TX_DP<120>")
		)
		(pad "2" smd rect
			(at 0.2667 0 90)
			(size 0.3048 0.381)
			(layers "F.Cu" "F.Mask" "F.Paste")
			(net "P5E_PEX2_STN7_TX_C_DP<120>")
		)
	)
)
